(kicad_pcb
	(version 20260206)
	(generator "pcbnew")
	(generator_version "10.0")
	(general
		(thickness 1.6)
		(legacy_teardrops no)
	)
	(paper "A4")
	(title_block
		(title "04192023_DAF0TMB3IC0_F0TG_MB_C_brd_V02_OCP.brd")
		(comment 1 "Grand Teton / footprints 4009-4012 of 8354")
	)
	(layers
		(0 "F.Cu" signal "TOP")
		(4 "In1.Cu" signal "GND")
		(6 "In2.Cu" signal "IN1")
		(8 "In3.Cu" signal "GND1")
		(10 "In4.Cu" signal "IN2")
		(12 "In5.Cu" signal "GND2")
		(14 "In6.Cu" signal "IN3")
		(16 "In7.Cu" signal "GND3")
		(18 "In8.Cu" signal "VCC")
		(20 "In9.Cu" signal "VCC1")
		(22 "In10.Cu" signal "GND4")
		(24 "In11.Cu" signal "IN4")
		(26 "In12.Cu" signal "GND5")
		(28 "In13.Cu" signal "IN5")
		(30 "In14.Cu" signal "GND6")
		(32 "In15.Cu" signal "IN6")
		(34 "In16.Cu" signal "GND7")
		(2 "B.Cu" signal "BOTTOM")
		(9 "F.Adhes" user "F.Adhesive")
		(11 "B.Adhes" user "B.Adhesive")
		(13 "F.Paste" user "Package Geometry/Pastemask Top")
		(15 "B.Paste" user "Package Geometry/Pastemask Bottom")
		(5 "F.SilkS" user "Ref Des/Silkscreen Top")
		(7 "B.SilkS" user "Ref Des/Silkscreen Bottom")
		(1 "F.Mask" user "Board Geometry/Soldermask Top")
		(3 "B.Mask" user "Board Geometry/Soldermask Bottom")
		(17 "Dwgs.User" user "User.Drawings")
		(19 "Cmts.User" user "User.Comments")
		(21 "Eco1.User" user "User.Eco1")
		(23 "Eco2.User" user "User.Eco2")
		(25 "Edge.Cuts" user "Board Geometry/Outline")
		(27 "Margin" user)
		(31 "F.CrtYd" user "Package Geometry/Place Bound Top")
		(29 "B.CrtYd" user "Package Geometry/Place Bound Bottom")
		(35 "F.Fab" user "Ref Des/Assembly Top")
		(33 "B.Fab" user "Ref Des/Assembly Bottom")
	)
	(footprint ""
		(layer "F.Cu")
		(at 300.364906 -346.71635)
		(property "Reference" "PU17"
			(at -3.057906 -7.58698 0)
			(unlocked yes)
			(layer "F.SilkS")
			(effects
				(font
					(size 0.7874 0.5842)
					(thickness 0.1524)
				)
				(justify left)
			)
		)
		(property "Value" ""
			(at 0 0 0)
			(layer "F.Fab")
			(effects
				(font
					(size 1.27 1.27)
				)
			)
		)
		(duplicate_pad_numbers_are_jumpers no)
		(fp_line
			(start -2.500122 -2.999994)
			(end -2.24409 -2.999994)
			(stroke
				(width 0.1524)
				(type default)
			)
			(layer "F.SilkS")
		)
		(fp_line
			(start -2.500122 -2.529078)
			(end -2.500122 -2.999994)
			(stroke
				(width 0.1524)
				(type default)
			)
			(layer "F.SilkS")
		)
		(fp_line
			(start -2.500122 0.6604)
			(end -2.500122 0.229108)
			(stroke
				(width 0.1524)
				(type default)
			)
			(layer "F.SilkS")
		)
		(fp_line
			(start -2.500122 2.999994)
			(end -2.500122 2.339594)
			(stroke
				(width 0.1524)
				(type default)
			)
			(layer "F.SilkS")
		)
		(fp_line
			(start -2.2987 2.999994)
			(end -2.500122 2.999994)
			(stroke
				(width 0.1524)
				(type default)
			)
			(layer "F.SilkS")
		)
		(fp_line
			(start 2.31394 -2.999994)
			(end 2.500122 -2.999994)
			(stroke
				(width 0.1524)
				(type default)
			)
			(layer "F.SilkS")
		)
		(fp_line
			(start 2.500122 -2.999994)
			(end 2.500122 -2.44348)
			(stroke
				(width 0.1524)
				(type default)
			)
			(layer "F.SilkS")
		)
		(fp_line
			(start 2.500122 2.339594)
			(end 2.500122 2.999994)
			(stroke
				(width 0.1524)
				(type default)
			)
			(layer "F.SilkS")
		)
		(fp_line
			(start 2.500122 2.999994)
			(end 2.2987 2.999994)
			(stroke
				(width 0.1524)
				(type default)
			)
			(layer "F.SilkS")
		)
		(fp_poly
			(pts
				(xy -3.438144 -2.695956) (xy -2.972562 -3.161538) (xy -2.740152 -2.463546)
			)
			(stroke
				(width 0)
				(type default)
			)
			(fill yes)
			(layer "F.SilkS")
		)
		(fp_line
			(start -2.500122 -2.999994)
			(end 2.500122 -2.999994)
			(stroke
				(width 0.1)
				(type default)
			)
			(layer "F.Fab")
		)
		(fp_line
			(start -2.500122 2.999994)
			(end -2.500122 -2.999994)
			(stroke
				(width 0.1)
				(type default)
			)
			(layer "F.Fab")
		)
		(fp_line
			(start 2.500122 -2.999994)
			(end 2.500122 2.999994)
			(stroke
				(width 0.1)
				(type default)
			)
			(layer "F.Fab")
		)
		(fp_line
			(start 2.500122 2.999994)
			(end -2.500122 2.999994)
			(stroke
				(width 0.1)
				(type default)
			)
			(layer "F.Fab")
		)
		(fp_poly
			(pts
				(xy -4.218432 -2.783078) (xy -4.218432 -1.767078) (xy -3.202432 -2.275078)
			)
			(stroke
				(width 0)
				(type default)
			)
			(fill yes)
			(layer "F.Fab")
		)
		(pad "1" smd rect
			(at -2.400046 -2.275078 90)
			(size 0.2286 0.6096)
			(layers "F.Cu" "F.Mask" "F.Paste")
			(net "PVDDIO_P0_VOS1")
		)
		(pad "2" smd rect
			(at -2.400046 -1.82499 90)
			(size 0.2286 0.6096)
			(layers "F.Cu" "F.Mask" "F.Paste")
			(net "GND")
		)
		(pad "3" smd rect
			(at -2.400046 -1.374902 90)
			(size 0.2286 0.6096)
			(layers "F.Cu" "F.Mask" "F.Paste")
			(net "PVDDIO_P0_VCC1")
		)
		(pad "4" smd rect
			(at -2.400046 -0.925068 90)
			(size 0.2286 0.6096)
			(layers "F.Cu" "F.Mask" "F.Paste")
			(net "PVDDCR_CPU1_P0_PVCC")
		)
		(pad "5" smd rect
			(at -2.400046 -0.47498 90)
			(size 0.2286 0.6096)
			(layers "F.Cu" "F.Mask" "F.Paste")
			(net "GND")
		)
		(pad "6" smd rect
			(at -2.400046 -0.024892 90)
			(size 0.2286 0.6096)
			(layers "F.Cu" "F.Mask" "F.Paste")
			(net "NC_PVDDIO_P0_GL1_1")
		)
		(pad "7_9-20_24" smd circle
			(at 0 1.150112 90)
			(size 0 0)
			(layers "F.Cu" "F.Mask" "F.Paste")
			(net "GND")
		)
		(pad "10_19" smd rect
			(at 0 2.899918 90)
			(size 0.6096 4.318)
			(layers "F.Cu" "F.Mask" "F.Paste")
			(net "SW_PVDDIO_P0_SW1")
		)
		(pad "25_29" smd rect
			(at 1.549908 -1.279906 270)
			(size 2.0574 2.3114)
			(layers "F.Cu" "F.Mask" "F.Paste")
			(net "SW_P12V_AUX_PVDDIO_P0_FLT")
		)
		(pad "30" smd rect
			(at 2.05994 -2.899918)
			(size 0.2286 0.6096)
			(layers "F.Cu" "F.Mask" "F.Paste")
			(net "SW_P12V_AUX_PVDDIO_P0_FLT")
		)
		(pad "31" smd rect
			(at 1.610106 -2.899918)
			(size 0.2286 0.6096)
			(layers "F.Cu" "F.Mask" "F.Paste")
			(net "NC_PVDDIO_P0_DNC1")
		)
		(pad "32" smd rect
			(at 1.160018 -2.899918)
			(size 0.2286 0.6096)
			(layers "F.Cu" "F.Mask" "F.Paste")
			(net "SW_PVDDIO_P0_BOOTR1")
		)
		(pad "33" smd rect
			(at 0.70993 -2.899918)
			(size 0.2286 0.6096)
			(layers "F.Cu" "F.Mask" "F.Paste")
			(net "SW_PVDDIO_P0_BOOT1")
		)
		(pad "34" smd rect
			(at 0.260096 -2.899918)
			(size 0.2286 0.6096)
			(layers "F.Cu" "F.Mask" "F.Paste")
			(net "PVDDIO_P0_PWM1")
		)
		(pad "35" smd rect
			(at -0.189992 -2.899918)
			(size 0.2286 0.6096)
			(layers "F.Cu" "F.Mask" "F.Paste")
			(net "PVDDIO_P0_VCC1")
		)
		(pad "36" smd rect
			(at -0.64008 -2.899918)
			(size 0.2286 0.6096)
			(layers "F.Cu" "F.Mask" "F.Paste")
			(net "PVDDIO_P0_TEMP1")
		)
		(pad "37" smd rect
			(at -1.089914 -2.899918)
			(size 0.2286 0.6096)
			(layers "F.Cu" "F.Mask" "F.Paste")
			(net "PVDDIO_P0_LSET1")
		)
		(pad "38" smd rect
			(at -1.540002 -2.899918)
			(size 0.2286 0.6096)
			(layers "F.Cu" "F.Mask" "F.Paste")
			(net "PVDDIO_P0_IMON1")
		)
		(pad "39" smd rect
			(at -1.99009 -2.899918)
			(size 0.2286 0.6096)
			(layers "F.Cu" "F.Mask" "F.Paste")
			(net "PVDDCR_CPU1_P0_VCCS")
		)
		(pad "40" smd rect
			(at -0.87503 -1.27508)
			(size 1.7526 1.9558)
			(layers "F.Cu" "F.Mask" "F.Paste")
			(net "GND")
		)
		(pad "41" smd rect
			(at -1.525016 0.249936 270)
			(size 0.3048 0.4572)
			(layers "F.Cu" "F.Mask" "F.Paste")
			(net "NC_PVDDIO_P0_GL2_1")
		)
		(zone
			(layer "F.Cu")
			(hatch none 0.5)
			(connect_pads
				(clearance 0)
			)
			(min_thickness 0.25)
			(keepout
				(tracks not_allowed)
				(vias allowed)
				(pads allowed)
				(copperpour not_allowed)
				(footprints allowed)
			)
			(placement
				(enabled no)
				(sheetname "")
			)
			(fill
				(thermal_gap 0.5)
				(thermal_bridge_width 0.5)
				(island_removal_mode 0)
			)
			(polygon
				(pts
					(xy 297.864784 -344.138758) (xy 297.864784 -344.465656) (xy 302.865028 -344.465656) (xy 302.865028 -344.130884)
					(xy 302.574706 -344.130884) (xy 302.574706 -344.172032) (xy 298.155106 -344.172032) (xy 298.155106 -344.138758)
				)
			)
		)
		(zone
			(layer "F.Cu")
			(hatch none 0.5)
			(connect_pads
				(clearance 0)
			)
			(min_thickness 0.25)
			(keepout
				(tracks not_allowed)
				(vias allowed)
				(pads allowed)
				(copperpour not_allowed)
				(footprints allowed)
			)
			(placement
				(enabled no)
				(sheetname "")
			)
			(fill
				(thermal_gap 0.5)
				(thermal_bridge_width 0.5)
				(island_removal_mode 0)
			)
			(polygon
				(pts
					(xy 300.416976 -346.96273) (xy 300.416976 -349.02013) (xy 298.562776 -349.02013) (xy 298.562776 -348.779084)
					(xy 298.32046 -348.779084) (xy 298.32046 -349.260668) (xy 302.123094 -349.260668) (xy 302.123094 -349.075756)
					(xy 300.708314 -349.075756) (xy 300.708314 -346.916756) (xy 302.865028 -346.916756) (xy 302.865028 -346.667074)
					(xy 300.661578 -346.667074) (xy 300.416976 -346.911676)
				)
			)
		)
	)
	(footprint ""
		(layer "F.Cu")
		(at 353.900232 -258.405122)
		(property "Reference" "C2599"
			(at 0 0 0)
			(layer "F.SilkS")
			(hide yes)
			(effects
				(font
					(size 1.27 1.27)
				)
			)
		)
		(property "Value" ""
			(at 0 0 0)
			(layer "F.Fab")
			(effects
				(font
					(size 1.27 1.27)
				)
			)
		)
		(duplicate_pad_numbers_are_jumpers no)
		(fp_line
			(start -0.7874 -0.4064)
			(end 0.7874 -0.4064)
			(stroke
				(width 0.1524)
				(type default)
			)
			(layer "F.SilkS")
		)
		(fp_line
			(start -0.7874 0.4064)
			(end -0.7874 -0.4064)
			(stroke
				(width 0.1524)
				(type default)
			)
			(layer "F.SilkS")
		)
		(fp_line
			(start 0.7874 -0.4064)
			(end 0.7874 0.4064)
			(stroke
				(width 0.1524)
				(type default)
			)
			(layer "F.SilkS")
		)
		(fp_line
			(start 0.7874 0.4064)
			(end -0.7874 0.4064)
			(stroke
				(width 0.1524)
				(type default)
			)
			(layer "F.SilkS")
		)
		(fp_line
			(start -0.67945 -0.305054)
			(end -0.12065 -0.305054)
			(stroke
				(width 0.1)
				(type default)
			)
			(layer "F.Fab")
		)
		(fp_line
			(start -0.67945 0.3048)
			(end -0.67945 -0.305054)
			(stroke
				(width 0.1)
				(type default)
			)
			(layer "F.Fab")
		)
		(fp_line
			(start -0.12065 -0.305054)
			(end -0.12065 -0.2794)
			(stroke
				(width 0.1)
				(type default)
			)
			(layer "F.Fab")
		)
		(fp_line
			(start -0.12065 -0.2794)
			(end 0.12065 -0.2794)
			(stroke
				(width 0.1)
				(type default)
			)
			(layer "F.Fab")
		)
		(fp_line
			(start -0.12065 0.2794)
			(end -0.12065 0.3048)
			(stroke
				(width 0.1)
				(type default)
			)
			(layer "F.Fab")
		)
		(fp_line
			(start -0.12065 0.3048)
			(end -0.67945 0.3048)
			(stroke
				(width 0.1)
				(type default)
			)
			(layer "F.Fab")
		)
		(fp_line
			(start 0.120396 0.2794)
			(end -0.12065 0.2794)
			(stroke
				(width 0.1)
				(type default)
			)
			(layer "F.Fab")
		)
		(fp_line
			(start 0.120396 0.3048)
			(end 0.120396 0.2794)
			(stroke
				(width 0.1)
				(type default)
			)
			(layer "F.Fab")
		)
		(fp_line
			(start 0.12065 -0.3048)
			(end 0.67945 -0.3048)
			(stroke
				(width 0.1)
				(type default)
			)
			(layer "F.Fab")
		)
		(fp_line
			(start 0.12065 -0.2794)
			(end 0.12065 -0.3048)
			(stroke
				(width 0.1)
				(type default)
			)
			(layer "F.Fab")
		)
		(fp_line
			(start 0.67945 -0.3048)
			(end 0.67945 0.3048)
			(stroke
				(width 0.1)
				(type default)
			)
			(layer "F.Fab")
		)
		(fp_line
			(start 0.67945 0.3048)
			(end 0.120396 0.3048)
			(stroke
				(width 0.1)
				(type default)
			)
			(layer "F.Fab")
		)
		(pad "1" smd circle
			(at -0.40005 0)
			(size 0 0)
			(layers "F.Cu" "F.Mask" "F.Paste")
			(net "PVDDIO_P0")
		)
		(pad "2" smd circle
			(at 0.40005 0)
			(size 0 0)
			(layers "F.Cu" "F.Mask" "F.Paste")
			(net "GND")
		)
	)
	(footprint ""
		(layer "F.Cu")
		(at 285.218124 -395.22019 -90)
		(property "Reference" "U143"
			(at 2.42951 -2.26187 90)
			(unlocked yes)
			(layer "F.SilkS")
			(effects
				(font
					(size 0.7874 0.5842)
					(thickness 0.1524)
				)
				(justify left)
			)
		)
		(property "Value" ""
			(at 0 0 270)
			(layer "F.Fab")
			(effects
				(font
					(size 1.27 1.27)
				)
			)
		)
		(duplicate_pad_numbers_are_jumpers no)
		(fp_line
			(start -1.448308 1.549908)
			(end -1.448308 -1.549908)
			(stroke
				(width 0.1524)
				(type default)
			)
			(layer "F.SilkS")
		)
		(fp_line
			(start 1.448308 1.549908)
			(end -1.448308 1.549908)
			(stroke
				(width 0.1524)
				(type default)
			)
			(layer "F.SilkS")
		)
		(fp_line
			(start 0 -0.533908)
			(end 0.774954 -1.549908)
			(stroke
				(width 0.1524)
				(type default)
			)
			(layer "F.SilkS")
		)
		(fp_line
			(start -1.448308 -1.549908)
			(end -0.774954 -1.549908)
			(stroke
				(width 0.1524)
				(type default)
			)
			(layer "F.SilkS")
		)
		(fp_line
			(start -0.774954 -1.549908)
			(end 0 -0.533908)
			(stroke
				(width 0.1524)
				(type default)
			)
			(layer "F.SilkS")
		)
		(fp_line
			(start 0.774954 -1.549908)
			(end 1.448308 -1.549908)
			(stroke
				(width 0.1524)
				(type default)
			)
			(layer "F.SilkS")
		)
		(fp_line
			(start 1.448308 -1.549908)
			(end 1.448308 1.549908)
			(stroke
				(width 0.1524)
				(type default)
			)
			(layer "F.SilkS")
		)
		(fp_rect
			(start -1.549908 -1.549908)
			(end -0.787908 -1.880108)
			(stroke
				(width 0)
				(type default)
			)
			(fill yes)
			(layer "F.SilkS")
		)
		(fp_line
			(start -1.549908 1.549908)
			(end -1.549908 -1.549908)
			(stroke
				(width 0.1)
				(type default)
			)
			(layer "F.Fab")
		)
		(fp_line
			(start 1.549908 1.549908)
			(end -1.549908 1.549908)
			(stroke
				(width 0.1)
				(type default)
			)
			(layer "F.Fab")
		)
		(fp_line
			(start -1.549908 -1.549908)
			(end 1.549908 -1.549908)
			(stroke
				(width 0.1)
				(type default)
			)
			(layer "F.Fab")
		)
		(fp_line
			(start 1.549908 -1.549908)
			(end 1.549908 1.549908)
			(stroke
				(width 0.1)
				(type default)
			)
			(layer "F.Fab")
		)
		(fp_poly
			(pts
				(xy -1.549908 -1.549908) (xy -0.787908 -1.549908) (xy -0.787908 -1.880108) (xy -1.549908 -1.880108)
			)
			(stroke
				(width 0)
				(type default)
			)
			(fill yes)
			(layer "F.Fab")
		)
		(pad "1" smd rect
			(at -2.350008 -0.975106 180)
			(size 0.4318 1.4986)
			(layers "F.Cu" "F.Mask" "F.Paste")
			(net "P3V3_AUX")
		)
		(pad "2" smd rect
			(at -2.350008 -0.32512 180)
			(size 0.4318 1.4986)
			(layers "F.Cu" "F.Mask" "F.Paste")
			(net "P12V_HSC_TEMP_D+")
		)
		(pad "3" smd rect
			(at -2.350008 0.32512 180)
			(size 0.4318 1.4986)
			(layers "F.Cu" "F.Mask" "F.Paste")
			(net "P12V_HSC_TEMP_D-")
		)
		(pad "4" smd rect
			(at -2.350008 0.975106 180)
			(size 0.4318 1.4986)
			(layers "F.Cu" "F.Mask" "F.Paste")
			(net "P12V_HSC_T_CRIT_N")
		)
		(pad "5" smd rect
			(at 2.350008 0.975106 180)
			(size 0.4318 1.4986)
			(layers "F.Cu" "F.Mask" "F.Paste")
			(net "GND")
		)
		(pad "6" smd rect
			(at 2.350008 0.32512 180)
			(size 0.4318 1.4986)
			(layers "F.Cu" "F.Mask" "F.Paste")
			(net "P12V_HSC_TEMP_ALERT_N")
		)
		(pad "7" smd rect
			(at 2.350008 -0.32512 180)
			(size 0.4318 1.4986)
			(layers "F.Cu" "F.Mask" "F.Paste")
			(net "SMB_P12V_HSC_TEMP_SDA")
		)
		(pad "8" smd rect
			(at 2.350008 -0.975106 180)
			(size 0.4318 1.4986)
			(layers "F.Cu" "F.Mask" "F.Paste")
			(net "SMB_P12V_HSC_TEMP_SCL")
		)
	)
	(footprint ""
		(layer "F.Cu")
		(at 273.183604 -108.194856 -90)
		(property "Reference" "R6070"
			(at 0 0 270)
			(layer "F.SilkS")
			(hide yes)
			(effects
				(font
					(size 1.27 1.27)
				)
			)
		)
		(property "Value" ""
			(at 0 0 270)
			(layer "F.Fab")
			(effects
				(font
					(size 1.27 1.27)
				)
			)
		)
		(duplicate_pad_numbers_are_jumpers no)
		(fp_line
			(start -0.7874 0.4064)
			(end -0.7874 -0.4064)
			(stroke
				(width 0.1524)
				(type default)
			)
			(layer "F.SilkS")
		)
		(fp_line
			(start 0.7874 0.4064)
			(end -0.7874 0.4064)
			(stroke
				(width 0.1524)
				(type default)
			)
			(layer "F.SilkS")
		)
		(fp_line
			(start -0.7874 -0.4064)
			(end 0.7874 -0.4064)
			(stroke
				(width 0.1524)
				(type default)
			)
			(layer "F.SilkS")
		)
		(fp_line
			(start 0.7874 -0.4064)
			(end 0.7874 0.4064)
			(stroke
				(width 0.1524)
				(type default)
			)
			(layer "F.SilkS")
		)
		(fp_line
			(start -0.67945 0.3048)
			(end -0.67945 -0.305054)
			(stroke
				(width 0.1)
				(type default)
			)
			(layer "F.Fab")
		)
		(fp_line
			(start -0.12065 0.3048)
			(end -0.67945 0.3048)
			(stroke
				(width 0.1)
				(type default)
			)
			(layer "F.Fab")
		)
		(fp_line
			(start 0.120396 0.3048)
			(end 0.120396 0.2794)
			(stroke
				(width 0.1)
				(type default)
			)
			(layer "F.Fab")
		)
		(fp_line
			(start 0.67945 0.3048)
			(end 0.120396 0.3048)
			(stroke
				(width 0.1)
				(type default)
			)
			(layer "F.Fab")
		)
		(fp_line
			(start -0.12065 0.2794)
			(end -0.12065 0.3048)
			(stroke
				(width 0.1)
				(type default)
			)
			(layer "F.Fab")
		)
		(fp_line
			(start 0.120396 0.2794)
			(end -0.12065 0.2794)
			(stroke
				(width 0.1)
				(type default)
			)
			(layer "F.Fab")
		)
		(fp_line
			(start -0.12065 -0.2794)
			(end 0.12065 -0.2794)
			(stroke
				(width 0.1)
				(type default)
			)
			(layer "F.Fab")
		)
		(fp_line
			(start 0.12065 -0.2794)
			(end 0.12065 -0.3048)
			(stroke
				(width 0.1)
				(type default)
			)
			(layer "F.Fab")
		)
		(fp_line
			(start 0.12065 -0.3048)
			(end 0.67945 -0.3048)
			(stroke
				(width 0.1)
				(type default)
			)
			(layer "F.Fab")
		)
		(fp_line
			(start 0.67945 -0.3048)
			(end 0.67945 0.3048)
			(stroke
				(width 0.1)
				(type default)
			)
			(layer "F.Fab")
		)
		(fp_line
			(start -0.67945 -0.305054)
			(end -0.12065 -0.305054)
			(stroke
				(width 0.1)
				(type default)
			)
			(layer "F.Fab")
		)
		(fp_line
			(start -0.12065 -0.305054)
			(end -0.12065 -0.2794)
			(stroke
				(width 0.1)
				(type default)
			)
			(layer "F.Fab")
		)
		(pad "1" smd circle
			(at -0.40005 0 270)
			(size 0 0)
			(layers "F.Cu" "F.Mask" "F.Paste")
			(net "P3V3_AUX")
		)
		(pad "2" smd circle
			(at 0.40005 0 270)
			(size 0 0)
			(layers "F.Cu" "F.Mask" "F.Paste")
			(net "JTAG_SCM_DBREQ_N")
		)
	)
)
